FILE_TYPE = CONNECTIVITY;
{Allegro Design Entry HDL 16.6-p007 (v16-6-112F) 10/10/2012}
"PAGE_NUMBER" = 10;
0"NC";
END.
